(kicad_pcb
	(version 20260206)
	(generator "pcbnew")
	(generator_version "10.0")
	(general
		(thickness 1.6)
		(legacy_teardrops no)
	)
	(paper "A4")
	(title_block
		(title "baseboard — 13948-1b.1110WZS1818.brd")
		(comment 1 "Honey Badger (Wiwynn) / footprints 78-83 of 2523")
	)
	(layers
		(0 "F.Cu" signal "TOP")
		(4 "In1.Cu" signal "L2GND")
		(6 "In2.Cu" signal "L3")
		(8 "In3.Cu" signal "L4VCC")
		(10 "In4.Cu" signal "L5VCC")
		(12 "In5.Cu" signal "L6")
		(14 "In6.Cu" signal "L7GND")
		(2 "B.Cu" signal "BOTTOM")
		(9 "F.Adhes" user "F.Adhesive")
		(11 "B.Adhes" user "B.Adhesive")
		(13 "F.Paste" user "Package Geometry/Pastemask Top")
		(15 "B.Paste" user "Package Geometry/Pastemask Bottom")
		(5 "F.SilkS" user "Ref Des/Silkscreen Top")
		(7 "B.SilkS" user "Ref Des/Silkscreen Bottom")
		(1 "F.Mask" user "Board Geometry/Soldermask Top")
		(3 "B.Mask" user "Board Geometry/Soldermask Bottom")
		(17 "Dwgs.User" user "User.Drawings")
		(19 "Cmts.User" user "User.Comments")
		(21 "Eco1.User" user "User.Eco1")
		(23 "Eco2.User" user "User.Eco2")
		(25 "Edge.Cuts" user "Board Geometry/Outline")
		(27 "Margin" user)
		(31 "F.CrtYd" user "Package Geometry/Place Bound Top")
		(29 "B.CrtYd" user "Package Geometry/Place Bound Bottom")
		(35 "F.Fab" user "Ref Des/Assembly Top")
		(33 "B.Fab" user "Ref Des/Assembly Bottom")
	)
	(footprint ""
		(layer "F.Cu")
		(at 16.333216 -211.00288 90)
		(property "Reference" "SR590"
			(at 0 0 90)
			(layer "F.SilkS")
			(hide yes)
			(effects
				(font
					(size 1.27 1.27)
				)
			)
		)
		(property "Value" "4K7R2F-GP"
			(at 0.064008 -3.993896 90)
			(unlocked yes)
			(layer "F.Fab")
			(hide yes)
			(effects
				(font
					(size 1.016 1.016)
					(thickness 0.1524)
				)
			)
		)
		(property "Device Type" "R402H16"
			(at 0.064008 -5.517896 90)
			(unlocked yes)
			(layer "F.Fab")
			(hide yes)
			(effects
				(font
					(size 1.016 1.016)
					(thickness 0.1524)
				)
			)
		)
		(duplicate_pad_numbers_are_jumpers no)
		(fp_line
			(start 0.508 -0.9398)
			(end -0.508 -0.9398)
			(stroke
				(width 0.1524)
				(type default)
			)
			(layer "F.SilkS")
		)
		(fp_line
			(start -0.508 -0.9398)
			(end -0.508 0.9398)
			(stroke
				(width 0.1524)
				(type default)
			)
			(layer "F.SilkS")
		)
		(fp_rect
			(start -0.508 0.9398)
			(end 0.508 -0.9398)
			(stroke
				(width 0)
				(type default)
			)
			(fill no)
			(layer "F.CrtYd")
		)
		(fp_rect
			(start -0.508 0.9398)
			(end 0.508 -0.9398)
			(stroke
				(width 0)
				(type default)
			)
			(fill no)
			(layer "F.Fab")
		)
		(pad "1" smd custom
			(at 0 -0.4445 90)
			(size 0.1397 0.1397)
			(layers "F.Cu" "F.Mask" "F.Paste")
			(net "BMC_IOEXP_SCL_10")
			(options
				(clearance outline)
				(anchor circle)
			)
			(primitives
				(gr_poly
					(pts
						(arc
							(start -0.1778 -0.2794)
							(mid -0.249642 -0.249642)
							(end -0.2794 -0.1778)
						)
						(arc
							(start -0.2794 0.1778)
							(mid -0.249642 0.249642)
							(end -0.1778 0.2794)
						)
						(arc
							(start 0.1778 0.2794)
							(mid 0.249642 0.249642)
							(end 0.2794 0.1778)
						)
						(arc
							(start 0.2794 -0.1778)
							(mid 0.249642 -0.249642)
							(end 0.1778 -0.2794)
						)
					)
					(width 0)
					(fill yes)
				)
			)
		)
		(pad "2" smd custom
			(at 0 0.4445 90)
			(size 0.1397 0.1397)
			(layers "F.Cu" "F.Mask" "F.Paste")
			(net "P1V8_E")
			(options
				(clearance outline)
				(anchor circle)
			)
			(primitives
				(gr_poly
					(pts
						(arc
							(start -0.1778 -0.2794)
							(mid -0.249642 -0.249642)
							(end -0.2794 -0.1778)
						)
						(arc
							(start -0.2794 0.1778)
							(mid -0.249642 0.249642)
							(end -0.1778 0.2794)
						)
						(arc
							(start 0.1778 0.2794)
							(mid 0.249642 0.249642)
							(end 0.2794 0.1778)
						)
						(arc
							(start 0.2794 -0.1778)
							(mid 0.249642 -0.249642)
							(end 0.1778 -0.2794)
						)
					)
					(width 0)
					(fill yes)
				)
			)
		)
	)
	(footprint ""
		(layer "F.Cu")
		(at 68.961 -228.092 180)
		(property "Reference" "D36"
			(at 0 0 180)
			(layer "F.SilkS")
			(hide yes)
			(effects
				(font
					(size 1.27 1.27)
				)
			)
		)
		(property "Value" "MM3Z15VT1G-GP-U"
			(at 0 -6.7818 180)
			(unlocked yes)
			(layer "F.Fab")
			(hide yes)
			(effects
				(font
					(size 1.016 1.016)
					(thickness 0.1524)
				)
			)
		)
		(property "Device Type" "SOD323AKH44"
			(at 0 -8.6868 180)
			(unlocked yes)
			(layer "F.Fab")
			(hide yes)
			(effects
				(font
					(size 1.016 1.016)
					(thickness 0.1524)
				)
			)
		)
		(duplicate_pad_numbers_are_jumpers no)
		(fp_line
			(start 0.889 2.159)
			(end -0.889 2.159)
			(stroke
				(width 0.1524)
				(type default)
			)
			(layer "F.SilkS")
		)
		(fp_line
			(start 0.889 -1.9304)
			(end 0.889 2.159)
			(stroke
				(width 0.1524)
				(type default)
			)
			(layer "F.SilkS")
		)
		(fp_line
			(start 0.762 2.0574)
			(end -0.762 2.0574)
			(stroke
				(width 0.508)
				(type default)
			)
			(layer "F.SilkS")
		)
		(fp_line
			(start -0.889 2.159)
			(end -0.889 -1.9304)
			(stroke
				(width 0.1524)
				(type default)
			)
			(layer "F.SilkS")
		)
		(fp_line
			(start -0.889 -1.9304)
			(end 0.889 -1.9304)
			(stroke
				(width 0.1524)
				(type default)
			)
			(layer "F.SilkS")
		)
		(fp_rect
			(start -1.016 2.3114)
			(end 1.016 -2.0066)
			(stroke
				(width 0)
				(type default)
			)
			(fill no)
			(layer "F.CrtYd")
		)
		(fp_poly
			(pts
				(xy -1.016 -2.0066) (xy 1.016 -2.0066) (xy 1.016 2.3114) (xy -1.016 2.3114)
			)
			(stroke
				(width 0)
				(type default)
			)
			(fill no)
			(layer "F.Fab")
		)
		(pad "A" smd rect
			(at 0 -1.143 180)
			(size 0.5588 1.016)
			(layers "F.Cu" "F.Mask" "F.Paste")
			(net "MB0_P12V_R")
		)
		(pad "K" smd rect
			(at 0 1.143 180)
			(size 0.5588 1.016)
			(layers "F.Cu" "F.Mask" "F.Paste")
			(net "MB0_CM_GATE_R")
		)
	)
	(footprint ""
		(layer "F.Cu")
		(at 330.484988 -75.946 -90)
		(property "Reference" "U195"
			(at 0 0 270)
			(layer "F.SilkS")
			(hide yes)
			(effects
				(font
					(size 1.27 1.27)
				)
			)
		)
		(property "Value" "W25Q128FVSIG-GP"
			(at 0 -13.1572 270)
			(unlocked yes)
			(layer "F.Fab")
			(hide yes)
			(effects
				(font
					(size 1.016 1.016)
					(thickness 0.1524)
				)
			)
		)
		(property "Device Type" "SOIC8-1H86"
			(at 0 -14.6812 270)
			(unlocked yes)
			(layer "F.Fab")
			(hide yes)
			(effects
				(font
					(size 1.016 1.016)
					(thickness 0.1524)
				)
			)
		)
		(duplicate_pad_numbers_are_jumpers no)
		(fp_line
			(start -3.048 4.572)
			(end -3.048 2.3876)
			(stroke
				(width 0.508)
				(type default)
			)
			(layer "F.SilkS")
		)
		(fp_line
			(start 2.1336 2.3876)
			(end -3.048 2.3876)
			(stroke
				(width 0.1524)
				(type default)
			)
			(layer "F.SilkS")
		)
		(fp_line
			(start -2.3114 0)
			(end -3.2258 0.9144)
			(stroke
				(width 0.1524)
				(type default)
			)
			(layer "F.SilkS")
		)
		(fp_line
			(start -2.3114 0)
			(end -3.2258 -0.9144)
			(stroke
				(width 0.1524)
				(type default)
			)
			(layer "F.SilkS")
		)
		(fp_line
			(start -3.2258 -2.3876)
			(end -3.2258 4.572)
			(stroke
				(width 0.1524)
				(type default)
			)
			(layer "F.SilkS")
		)
		(fp_line
			(start 2.1336 -2.3876)
			(end 2.1336 2.3876)
			(stroke
				(width 0.1524)
				(type default)
			)
			(layer "F.SilkS")
		)
		(fp_line
			(start 2.1336 -2.3876)
			(end -3.2258 -2.3876)
			(stroke
				(width 0.1524)
				(type default)
			)
			(layer "F.SilkS")
		)
		(fp_poly
			(pts
				(xy -2.2352 2.3876) (xy 2.1336 2.3876) (xy 2.1336 -2.3876) (xy -2.2352 -2.3876)
			)
			(stroke
				(width 0)
				(type default)
			)
			(fill yes)
			(layer "F.SilkS")
		)
		(fp_poly
			(pts
				(xy -3.302 4.826) (xy 3.302 4.826) (xy 3.302 -4.826) (xy -3.302 -4.826)
			)
			(stroke
				(width 0)
				(type default)
			)
			(fill no)
			(layer "F.CrtYd")
		)
		(fp_poly
			(pts
				(xy -3.302 -4.826) (xy 3.302 -4.826) (xy 3.302 4.826) (xy -3.302 4.826)
			)
			(stroke
				(width 0)
				(type default)
			)
			(fill no)
			(layer "F.Fab")
		)
		(pad "1" smd rect
			(at -1.905 3.4925 270)
			(size 0.635 1.651)
			(layers "F.Cu" "F.Mask" "F.Paste")
			(net "FLA_CS_1")
		)
		(pad "2" smd rect
			(at -0.635 3.4925 270)
			(size 0.635 1.651)
			(layers "F.Cu" "F.Mask" "F.Paste")
			(net "ROMD2_R_R")
		)
		(pad "3" smd rect
			(at 0.635 3.4925 270)
			(size 0.635 1.651)
			(layers "F.Cu" "F.Mask" "F.Paste")
			(net "FLA_WPN")
		)
		(pad "4" smd rect
			(at 1.905 3.4925 270)
			(size 0.635 1.651)
			(layers "F.Cu" "F.Mask" "F.Paste")
			(net "GND")
		)
		(pad "5" smd rect
			(at 1.905 -3.4925 270)
			(size 0.635 1.651)
			(layers "F.Cu" "F.Mask" "F.Paste")
			(net "ROMD0_R_R")
		)
		(pad "6" smd rect
			(at 0.635 -3.4925 270)
			(size 0.635 1.651)
			(layers "F.Cu" "F.Mask" "F.Paste")
			(net "ROMD1_R_R")
		)
		(pad "7" smd rect
			(at -0.635 -3.4925 270)
			(size 0.635 1.651)
			(layers "F.Cu" "F.Mask" "F.Paste")
			(net "PU_IBMC_BT_HOLD_N")
		)
		(pad "8" smd rect
			(at -1.905 -3.4925 270)
			(size 0.635 1.651)
			(layers "F.Cu" "F.Mask" "F.Paste")
			(net "P3V3_STBY")
		)
	)
	(footprint ""
		(layer "F.Cu")
		(at 202.888596 -110.636812 180)
		(property "Reference" "PR9016"
			(at 0 0 180)
			(layer "F.SilkS")
			(hide yes)
			(effects
				(font
					(size 1.27 1.27)
				)
			)
		)
		(property "Value" "0R2J-2-GP"
			(at 0.064008 -3.993896 180)
			(unlocked yes)
			(layer "F.Fab")
			(hide yes)
			(effects
				(font
					(size 1.016 1.016)
					(thickness 0.1524)
				)
			)
		)
		(property "Device Type" "R402H16"
			(at 0.064008 -5.517896 180)
			(unlocked yes)
			(layer "F.Fab")
			(hide yes)
			(effects
				(font
					(size 1.016 1.016)
					(thickness 0.1524)
				)
			)
		)
		(duplicate_pad_numbers_are_jumpers no)
		(fp_line
			(start 0.508 -0.9398)
			(end -0.508 -0.9398)
			(stroke
				(width 0.1524)
				(type default)
			)
			(layer "F.SilkS")
		)
		(fp_line
			(start -0.508 -0.9398)
			(end -0.508 0.9398)
			(stroke
				(width 0.1524)
				(type default)
			)
			(layer "F.SilkS")
		)
		(fp_rect
			(start -0.508 0.9398)
			(end 0.508 -0.9398)
			(stroke
				(width 0)
				(type default)
			)
			(fill no)
			(layer "F.CrtYd")
		)
		(fp_rect
			(start -0.508 0.9398)
			(end 0.508 -0.9398)
			(stroke
				(width 0)
				(type default)
			)
			(fill no)
			(layer "F.Fab")
		)
		(pad "1" smd custom
			(at 0 -0.4445 180)
			(size 0.1397 0.1397)
			(layers "F.Cu" "F.Mask" "F.Paste")
			(net "P1V5_E_VBST_RR")
			(options
				(clearance outline)
				(anchor circle)
			)
			(primitives
				(gr_poly
					(pts
						(arc
							(start -0.1778 -0.2794)
							(mid -0.249642 -0.249642)
							(end -0.2794 -0.1778)
						)
						(arc
							(start -0.2794 0.1778)
							(mid -0.249642 0.249642)
							(end -0.1778 0.2794)
						)
						(arc
							(start 0.1778 0.2794)
							(mid 0.249642 0.249642)
							(end 0.2794 0.1778)
						)
						(arc
							(start 0.2794 -0.1778)
							(mid 0.249642 -0.249642)
							(end 0.1778 -0.2794)
						)
					)
					(width 0)
					(fill yes)
				)
			)
		)
		(pad "2" smd custom
			(at 0 0.4445 180)
			(size 0.1397 0.1397)
			(layers "F.Cu" "F.Mask" "F.Paste")
			(net "P1V5_E_VBST")
			(options
				(clearance outline)
				(anchor circle)
			)
			(primitives
				(gr_poly
					(pts
						(arc
							(start -0.1778 -0.2794)
							(mid -0.249642 -0.249642)
							(end -0.2794 -0.1778)
						)
						(arc
							(start -0.2794 0.1778)
							(mid -0.249642 0.249642)
							(end -0.1778 0.2794)
						)
						(arc
							(start 0.1778 0.2794)
							(mid 0.249642 0.249642)
							(end 0.2794 0.1778)
						)
						(arc
							(start 0.2794 -0.1778)
							(mid 0.249642 -0.249642)
							(end 0.1778 -0.2794)
						)
					)
					(width 0)
					(fill yes)
				)
			)
		)
	)
	(footprint ""
		(layer "F.Cu")
		(at 349.123 -112.776 180)
		(property "Reference" "PR5"
			(at 0 0 180)
			(layer "F.SilkS")
			(hide yes)
			(effects
				(font
					(size 1.27 1.27)
				)
			)
		)
		(property "Value" "0R6J-3-GP"
			(at -0.0508 -4.8514 180)
			(unlocked yes)
			(layer "F.Fab")
			(hide yes)
			(effects
				(font
					(size 1.016 1.016)
					(thickness 0.1524)
				)
			)
		)
		(property "Device Type" "R1206H28"
			(at 0 -6.3754 180)
			(unlocked yes)
			(layer "F.Fab")
			(hide yes)
			(effects
				(font
					(size 1.016 1.016)
					(thickness 0.1524)
				)
			)
		)
		(duplicate_pad_numbers_are_jumpers no)
		(fp_line
			(start 1.016 2.2352)
			(end -1.016 2.2352)
			(stroke
				(width 0.1524)
				(type default)
			)
			(layer "F.SilkS")
		)
		(fp_line
			(start 1.016 -2.2352)
			(end 1.016 2.2352)
			(stroke
				(width 0.1524)
				(type default)
			)
			(layer "F.SilkS")
		)
		(fp_line
			(start -1.016 2.2352)
			(end -1.016 -2.2352)
			(stroke
				(width 0.1524)
				(type default)
			)
			(layer "F.SilkS")
		)
		(fp_line
			(start -1.016 -2.2352)
			(end 1.016 -2.2352)
			(stroke
				(width 0.1524)
				(type default)
			)
			(layer "F.SilkS")
		)
		(fp_rect
			(start -1.0922 2.3114)
			(end 1.0922 -2.3114)
			(stroke
				(width 0)
				(type default)
			)
			(fill no)
			(layer "F.CrtYd")
		)
		(fp_poly
			(pts
				(xy -1.0922 -2.3114) (xy 1.0922 -2.3114) (xy 1.0922 2.3114) (xy -1.0922 2.3114)
			)
			(stroke
				(width 0)
				(type default)
			)
			(fill no)
			(layer "F.Fab")
		)
		(pad "1" smd rect
			(at 0 -1.397 180)
			(size 1.651 1.27)
			(layers "F.Cu" "F.Mask" "F.Paste")
			(net "P5V_STBY_VIN")
		)
		(pad "2" smd rect
			(at 0 1.397 180)
			(size 1.651 1.27)
			(layers "F.Cu" "F.Mask" "F.Paste")
			(net "P12V")
		)
	)
	(footprint ""
		(layer "F.Cu")
		(at 81.031842 -117.927882 -90)
		(property "Reference" "SR755"
			(at 0 0 270)
			(layer "F.SilkS")
			(hide yes)
			(effects
				(font
					(size 1.27 1.27)
				)
			)
		)
		(property "Value" "4K7R2F-GP"
			(at 0.064008 -3.993896 270)
			(unlocked yes)
			(layer "F.Fab")
			(hide yes)
			(effects
				(font
					(size 1.016 1.016)
					(thickness 0.1524)
				)
			)
		)
		(property "Device Type" "R402H16"
			(at 0.064008 -5.517896 270)
			(unlocked yes)
			(layer "F.Fab")
			(hide yes)
			(effects
				(font
					(size 1.016 1.016)
					(thickness 0.1524)
				)
			)
		)
		(duplicate_pad_numbers_are_jumpers no)
		(fp_line
			(start -0.508 -0.9398)
			(end -0.508 0.9398)
			(stroke
				(width 0.1524)
				(type default)
			)
			(layer "F.SilkS")
		)
		(fp_line
			(start 0.508 -0.9398)
			(end -0.508 -0.9398)
			(stroke
				(width 0.1524)
				(type default)
			)
			(layer "F.SilkS")
		)
		(fp_rect
			(start -0.508 0.9398)
			(end 0.508 -0.9398)
			(stroke
				(width 0)
				(type default)
			)
			(fill no)
			(layer "F.CrtYd")
		)
		(fp_rect
			(start -0.508 0.9398)
			(end 0.508 -0.9398)
			(stroke
				(width 0)
				(type default)
			)
			(fill no)
			(layer "F.Fab")
		)
		(pad "1" smd custom
			(at 0 -0.4445 270)
			(size 0.1397 0.1397)
			(layers "F.Cu" "F.Mask" "F.Paste")
			(net "EXP_IOC_BMC_SDA_14")
			(options
				(clearance outline)
				(anchor circle)
			)
			(primitives
				(gr_poly
					(pts
						(arc
							(start -0.1778 -0.2794)
							(mid -0.249642 -0.249642)
							(end -0.2794 -0.1778)
						)
						(arc
							(start -0.2794 0.1778)
							(mid -0.249642 0.249642)
							(end -0.1778 0.2794)
						)
						(arc
							(start 0.1778 0.2794)
							(mid 0.249642 0.249642)
							(end 0.2794 0.1778)
						)
						(arc
							(start 0.2794 -0.1778)
							(mid 0.249642 -0.249642)
							(end 0.1778 -0.2794)
						)
					)
					(width 0)
					(fill yes)
				)
			)
		)
		(pad "2" smd custom
			(at 0 0.4445 270)
			(size 0.1397 0.1397)
			(layers "F.Cu" "F.Mask" "F.Paste")
			(net "P3V3_STBY")
			(options
				(clearance outline)
				(anchor circle)
			)
			(primitives
				(gr_poly
					(pts
						(arc
							(start -0.1778 -0.2794)
							(mid -0.249642 -0.249642)
							(end -0.2794 -0.1778)
						)
						(arc
							(start -0.2794 0.1778)
							(mid -0.249642 0.249642)
							(end -0.1778 0.2794)
						)
						(arc
							(start 0.1778 0.2794)
							(mid 0.249642 0.249642)
							(end 0.2794 0.1778)
						)
						(arc
							(start 0.2794 -0.1778)
							(mid 0.249642 -0.249642)
							(end 0.1778 -0.2794)
						)
					)
					(width 0)
					(fill yes)
				)
			)
		)
	)
)
